(kicad_pcb
	(version 20240108)
	(generator "pcbnew")
	(generator_version "8.0")
	(general
		(thickness 1.586)
		(legacy_teardrops no)
	)
	(paper "A4")
	(title_block
		(title "GMSL Serializer")
		(date "2024-11-27")
		(rev "1.1.1")
		(company "Antmicro Ltd")
		(comment 1 "www.antmicro.com")
		(comment 9 "footprints 93-96 of 117")
	)
	(layers
		(0 "F.Cu" signal)
		(1 "In1.Cu" power)
		(2 "In2.Cu" power)
		(31 "B.Cu" signal)
		(32 "B.Adhes" user "B.Adhesive")
		(33 "F.Adhes" user "F.Adhesive")
		(34 "B.Paste" user)
		(35 "F.Paste" user)
		(36 "B.SilkS" user "B.Silkscreen")
		(37 "F.SilkS" user "F.Silkscreen")
		(38 "B.Mask" user)
		(39 "F.Mask" user)
		(40 "Dwgs.User" user "User.Drawings")
		(41 "Cmts.User" user "User.Comments")
		(42 "Eco1.User" user "User.Eco1")
		(43 "Eco2.User" user "User.Eco2")
		(44 "Edge.Cuts" user)
		(45 "Margin" user)
		(46 "B.CrtYd" user "B.Courtyard")
		(47 "F.CrtYd" user "F.Courtyard")
		(48 "B.Fab" user)
		(49 "F.Fab" user)
	)
	(footprint "antmicro-footprints:R_0603_1608Metric"
		(layer "F.Cu")
		(at 145.295 88.670142 -90)
		(descr "Resistor SMD 0603")
		(tags "resistor SMD 0603")
		(property "Reference" "R45"
			(at 0.279858 -0.755 90)
			(layer "F.SilkS")
			(effects
				(font
					(size 0.7 0.7)
					(thickness 0.15)
				)
				(justify right top)
			)
		)
		(property "Value" "R_0R_22.4A_0603"
			(at 0 1.6 90)
			(layer "F.Fab")
			(effects
				(font
					(size 0.7 0.7)
					(thickness 0.15)
				)
				(justify right top)
			)
		)
		(property "Footprint" "antmicro-footprints:R_0603_1608Metric"
			(at 0 0 90)
			(layer "F.Fab")
			(hide yes)
			(effects
				(font
					(size 1.27 1.27)
					(thickness 0.15)
				)
			)
		)
		(property "Datasheet" "https://fscdn.rohm.com/en/products/databook/datasheet/passive/resistor/chip_resistor/pmr-jpw-e.pdf"
			(at 0 0 90)
			(layer "F.Fab")
			(hide yes)
			(effects
				(font
					(size 1.27 1.27)
					(thickness 0.15)
				)
			)
		)
		(property "MPN" "PMR03EZPJ000"
			(at 0 0 -90)
			(unlocked yes)
			(layer "F.Fab")
			(hide yes)
			(effects
				(font
					(size 1 1)
					(thickness 0.15)
				)
			)
		)
		(property "Manufacturer" "ROHM Semiconductor"
			(at 0 0 -90)
			(unlocked yes)
			(layer "F.Fab")
			(hide yes)
			(effects
				(font
					(size 1 1)
					(thickness 0.15)
				)
			)
		)
		(property "Val" "0R"
			(at 0 0 -90)
			(unlocked yes)
			(layer "F.Fab")
			(hide yes)
			(effects
				(font
					(size 1 1)
					(thickness 0.15)
				)
			)
		)
		(property "Max. Curr." "22.4A"
			(at 0 0 -90)
			(unlocked yes)
			(layer "F.Fab")
			(hide yes)
			(effects
				(font
					(size 1 1)
					(thickness 0.15)
				)
			)
		)
		(property "Author" "Antmicro"
			(at 0 0 -90)
			(unlocked yes)
			(layer "F.Fab")
			(hide yes)
			(effects
				(font
					(size 1 1)
					(thickness 0.15)
				)
			)
		)
		(property "License" "Apache-2.0"
			(at 0 0 -90)
			(unlocked yes)
			(layer "F.Fab")
			(hide yes)
			(effects
				(font
					(size 1 1)
					(thickness 0.15)
				)
			)
		)
		(property "Tolerance" "template_tolerance"
			(at 0 0 -90)
			(unlocked yes)
			(layer "F.Fab")
			(hide yes)
			(effects
				(font
					(size 1 1)
					(thickness 0.15)
				)
			)
		)
		(sheetname "Supply")
		(sheetfile "supply.kicad_sch")
		(attr smd)
		(fp_line
			(start -0.15 0.4)
			(end 0.15 0.4)
			(stroke
				(width 0.15)
				(type solid)
			)
			(layer "F.SilkS")
		)
		(fp_line
			(start -0.15 -0.4)
			(end 0.15 -0.4)
			(stroke
				(width 0.15)
				(type solid)
			)
			(layer "F.SilkS")
		)
		(fp_rect
			(start -1.25 -0.65)
			(end 1.25 0.65)
			(stroke
				(width 0.05)
				(type solid)
			)
			(fill none)
			(layer "F.CrtYd")
		)
		(fp_rect
			(start -0.8 -0.4)
			(end 0.8 0.4)
			(stroke
				(width 0.15)
				(type solid)
			)
			(fill none)
			(layer "F.Fab")
		)
		(fp_text user "Author: Antmicro"
			(at -1.25 4.9 90)
			(layer "F.Fab")
			(hide yes)
			(effects
				(font
					(size 0.7 0.7)
					(thickness 0.15)
				)
				(justify right top)
			)
		)
		(fp_text user "${REFERENCE}"
			(at -1.25 3.898 90)
			(layer "F.Fab")
			(hide yes)
			(effects
				(font
					(size 0.7 0.7)
					(thickness 0.15)
				)
				(justify right top)
			)
		)
		(fp_text user "License: Apache-2.0"
			(at -1.25 5.9 90)
			(layer "F.Fab")
			(hide yes)
			(effects
				(font
					(size 0.7 0.7)
					(thickness 0.15)
				)
				(justify right top)
			)
		)
		(pad "1" smd roundrect
			(at -0.7 0 270)
			(size 0.8 1)
			(layers "F.Cu" "F.Paste" "F.Mask")
			(roundrect_rratio 0.2)
			(net 94 "/Supply/OUT_3V3")
			(pintype "passive")
		)
		(pad "2" smd roundrect
			(at 0.7 0 270)
			(size 0.8 1)
			(layers "F.Cu" "F.Paste" "F.Mask")
			(roundrect_rratio 0.2)
			(net 10 "+3V3")
			(pintype "passive")
		)
	)
	(footprint "antmicro-footprints:C_0603_1608Metric"
		(layer "F.Cu")
		(at 136.755 83.1 90)
		(descr "Capacitor SMD 0603")
		(tags "capacitor 0603")
		(property "Reference" "C1"
			(at 0.28 0.485 180)
			(layer "F.SilkS")
			(effects
				(font
					(size 0.7 0.7)
					(thickness 0.15)
				)
				(justify left bottom)
			)
		)
		(property "Value" "C_10u_25V_0603"
			(at -1.42757 1.770288 90)
			(layer "F.Fab")
			(effects
				(font
					(size 0.7 0.7)
					(thickness 0.15)
				)
				(justify left bottom)
			)
		)
		(property "Footprint" "antmicro-footprints:C_0603_1608Metric"
			(at 0 0 90)
			(layer "F.Fab")
			(hide yes)
			(effects
				(font
					(size 1.27 1.27)
					(thickness 0.15)
				)
			)
		)
		(property "Datasheet" "https://product.tdk.com/en/search/capacitor/ceramic/mlcc/info?part_no=C1608X5R1E106M080AC"
			(at 0 0 90)
			(layer "F.Fab")
			(hide yes)
			(effects
				(font
					(size 1.27 1.27)
					(thickness 0.15)
				)
			)
		)
		(property "Author" "Antmicro"
			(at 221.475 -55.575 0)
			(layer "F.Fab")
			(hide yes)
			(effects
				(font
					(size 1 1)
					(thickness 0.15)
				)
			)
		)
		(property "Dielectric" ""
			(at 221.475 -55.575 0)
			(layer "F.Fab")
			(hide yes)
			(effects
				(font
					(size 1 1)
					(thickness 0.15)
				)
			)
		)
		(property "License" "Apache-2.0"
			(at 221.475 -55.575 0)
			(layer "F.Fab")
			(hide yes)
			(effects
				(font
					(size 1 1)
					(thickness 0.15)
				)
			)
		)
		(property "MPN" "C1608X5R1E106M080AC"
			(at 221.475 -55.575 0)
			(layer "F.Fab")
			(hide yes)
			(effects
				(font
					(size 1 1)
					(thickness 0.15)
				)
			)
		)
		(property "Manufacturer" "TDK"
			(at 221.475 -55.575 0)
			(layer "F.Fab")
			(hide yes)
			(effects
				(font
					(size 1 1)
					(thickness 0.15)
				)
			)
		)
		(property "Val" "10u"
			(at 221.475 -55.575 0)
			(layer "F.Fab")
			(hide yes)
			(effects
				(font
					(size 1 1)
					(thickness 0.15)
				)
			)
		)
		(property "Voltage" "25V"
			(at 221.475 -55.575 0)
			(layer "F.Fab")
			(hide yes)
			(effects
				(font
					(size 1 1)
					(thickness 0.15)
				)
			)
		)
		(sheetname "Supply")
		(sheetfile "supply.kicad_sch")
		(attr smd)
		(fp_line
			(start -0.15 -0.4)
			(end 0.15 -0.4)
			(stroke
				(width 0.15)
				(type solid)
			)
			(layer "F.SilkS")
		)
		(fp_line
			(start -0.15 0.4)
			(end 0.15 0.4)
			(stroke
				(width 0.15)
				(type solid)
			)
			(layer "F.SilkS")
		)
		(fp_rect
			(start -1.25 -0.65)
			(end 1.25 0.65)
			(stroke
				(width 0.05)
				(type solid)
			)
			(fill none)
			(layer "F.CrtYd")
		)
		(fp_rect
			(start -0.8 -0.4)
			(end 0.8 0.4)
			(stroke
				(width 0.15)
				(type solid)
			)
			(fill none)
			(layer "F.Fab")
		)
		(fp_text user "Author: Antmicro"
			(at -1.682 4.894 90)
			(layer "F.Fab")
			(hide yes)
			(effects
				(font
					(size 0.7 0.7)
					(thickness 0.15)
				)
				(justify left bottom)
			)
		)
		(fp_text user "${REFERENCE}"
			(at -1.682 3.895 90)
			(layer "F.Fab")
			(hide yes)
			(effects
				(font
					(size 0.7 0.7)
					(thickness 0.15)
				)
				(justify left bottom)
			)
		)
		(fp_text user "License: Apache-2.0"
			(at -1.682 5.895 90)
			(layer "F.Fab")
			(hide yes)
			(effects
				(font
					(size 0.7 0.7)
					(thickness 0.15)
				)
				(justify left bottom)
			)
		)
		(pad "1" smd roundrect
			(at -0.7 0 90)
			(size 0.8 1)
			(layers "F.Cu" "F.Paste" "F.Mask")
			(roundrect_rratio 0.2)
			(net 1 "GND")
			(pintype "passive")
		)
		(pad "2" smd roundrect
			(at 0.7 0 90)
			(size 0.8 1)
			(layers "F.Cu" "F.Paste" "F.Mask")
			(roundrect_rratio 0.2)
			(net 2 "+12V")
			(pintype "passive")
		)
	)
	(footprint "antmicro-footprints:L_Bourns-SRP3212A"
		(layer "F.Cu")
		(at 133.779 86.95)
		(property "Reference" "L1"
			(at -3.449 0.4 0)
			(layer "F.SilkS")
			(effects
				(font
					(size 0.7 0.7)
					(thickness 0.15)
				)
				(justify left bottom)
			)
		)
		(property "Value" "L_3u3_3.1A_Bourns-SRP3212A"
			(at 0.05 2.8 0)
			(layer "F.Fab")
			(effects
				(font
					(size 0.7 0.7)
					(thickness 0.15)
				)
				(justify left bottom)
			)
		)
		(property "Footprint" "antmicro-footprints:L_Bourns-SRP3212A"
			(at 0 0 0)
			(layer "F.Fab")
			(hide yes)
			(effects
				(font
					(size 1.27 1.27)
					(thickness 0.15)
				)
			)
		)
		(property "Datasheet" "https://www.mouser.com/datasheet/2/54/SRP3212A-3011944.pdf"
			(at 0 0 0)
			(layer "F.Fab")
			(hide yes)
			(effects
				(font
					(size 1.27 1.27)
					(thickness 0.15)
				)
			)
		)
		(property "Author" "Antmicro"
			(at 0 0 0)
			(layer "F.Fab")
			(hide yes)
			(effects
				(font
					(size 1 1)
					(thickness 0.15)
				)
			)
		)
		(property "IMax" "3.1 A"
			(at 0 0 0)
			(layer "F.Fab")
			(hide yes)
			(effects
				(font
					(size 1 1)
					(thickness 0.15)
				)
			)
		)
		(property "ISat" "3.4 A"
			(at 0 0 0)
			(layer "F.Fab")
			(hide yes)
			(effects
				(font
					(size 1 1)
					(thickness 0.15)
				)
			)
		)
		(property "License" "Apache-2.0"
			(at 0 0 0)
			(layer "F.Fab")
			(hide yes)
			(effects
				(font
					(size 1 1)
					(thickness 0.15)
				)
			)
		)
		(property "MPN" "SRP3212-3R3M"
			(at 0 0 0)
			(layer "F.Fab")
			(hide yes)
			(effects
				(font
					(size 1 1)
					(thickness 0.15)
				)
			)
		)
		(property "Manufacturer" "Bourns"
			(at 0 0 0)
			(layer "F.Fab")
			(hide yes)
			(effects
				(font
					(size 1 1)
					(thickness 0.15)
				)
			)
		)
		(property "Size" "3.2x2.5"
			(at 0 0 0)
			(layer "F.Fab")
			(hide yes)
			(effects
				(font
					(size 1 1)
					(thickness 0.15)
				)
			)
		)
		(property "Val" "3u3/3.1A"
			(at 0 0 0)
			(layer "F.Fab")
			(hide yes)
			(effects
				(font
					(size 1 1)
					(thickness 0.15)
				)
			)
		)
		(sheetname "Supply")
		(sheetfile "supply.kicad_sch")
		(attr smd)
		(fp_line
			(start -0.4 -1.25)
			(end 0.399 -1.25)
			(stroke
				(width 0.15)
				(type solid)
			)
			(layer "F.SilkS")
		)
		(fp_line
			(start -0.4 1.249)
			(end 0.399 1.249)
			(stroke
				(width 0.15)
				(type solid)
			)
			(layer "F.SilkS")
		)
		(fp_rect
			(start -2.1 -1.65)
			(end 2.1 1.65)
			(stroke
				(width 0.05)
				(type solid)
			)
			(fill none)
			(layer "F.CrtYd")
		)
		(fp_rect
			(start -1.609 -1.26)
			(end 1.609 1.26)
			(stroke
				(width 0.15)
				(type solid)
			)
			(fill none)
			(layer "F.Fab")
		)
		(fp_text user "${REFERENCE}"
			(at -2.1 4.8 0)
			(layer "F.Fab")
			(hide yes)
			(effects
				(font
					(size 0.7 0.7)
					(thickness 0.15)
				)
				(justify left bottom)
			)
		)
		(fp_text user "Author: Antmicro"
			(at -2.1 6 0)
			(layer "F.Fab")
			(hide yes)
			(effects
				(font
					(size 0.7 0.7)
					(thickness 0.15)
				)
				(justify left bottom)
			)
		)
		(fp_text user "License: Apache-2.0"
			(at -2.1 7.2 0)
			(layer "F.Fab")
			(hide yes)
			(effects
				(font
					(size 0.7 0.7)
					(thickness 0.15)
				)
				(justify left bottom)
			)
		)
		(pad "1" smd roundrect
			(at -1.175 0)
			(size 1.35 2.8)
			(layers "F.Cu" "F.Paste" "F.Mask")
			(roundrect_rratio 0.1)
			(net 4 "/Supply/SW_5V")
			(pintype "passive")
		)
		(pad "2" smd roundrect
			(at 1.175 0)
			(size 1.35 2.8)
			(layers "F.Cu" "F.Paste" "F.Mask")
			(roundrect_rratio 0.1)
			(net 7 "/Supply/OUT_5V")
			(pintype "passive")
		)
	)
	(footprint "antmicro-footprints:SOT-523"
		(layer "F.Cu")
		(at 147.425 113.225 90)
		(property "Reference" "Q3"
			(at -0.225 -1.175 90)
			(layer "F.SilkS")
			(effects
				(font
					(size 0.7 0.7)
					(thickness 0.15)
				)
				(justify left bottom)
			)
		)
		(property "Value" "DMG1012T-7"
			(at 0.1 1.824 90)
			(layer "F.Fab")
			(effects
				(font
					(size 0.7 0.7)
					(thickness 0.15)
				)
				(justify left bottom)
			)
		)
		(property "Footprint" "antmicro-footprints:SOT-523"
			(at 0 0 90)
			(layer "F.Fab")
			(hide yes)
			(effects
				(font
					(size 1.27 1.27)
					(thickness 0.15)
				)
			)
		)
		(property "Datasheet" "https://www.diodes.com/assets/Datasheets/ds31783.pdf"
			(at 0 0 90)
			(layer "F.Fab")
			(hide yes)
			(effects
				(font
					(size 1.27 1.27)
					(thickness 0.15)
				)
			)
		)
		(property "Author" "Antmicro"
			(at 260.65 -34.2 0)
			(layer "F.Fab")
			(hide yes)
			(effects
				(font
					(size 1 1)
					(thickness 0.15)
				)
			)
		)
		(property "License" "Apache-2.0"
			(at 260.65 -34.2 0)
			(layer "F.Fab")
			(hide yes)
			(effects
				(font
					(size 1 1)
					(thickness 0.15)
				)
			)
		)
		(property "MPN" "DMG1012T-7"
			(at 260.65 -34.2 0)
			(layer "F.Fab")
			(hide yes)
			(effects
				(font
					(size 1 1)
					(thickness 0.15)
				)
			)
		)
		(property "Manufacturer" "Diodes Incorporated"
			(at 260.65 -34.2 0)
			(layer "F.Fab")
			(hide yes)
			(effects
				(font
					(size 1 1)
					(thickness 0.15)
				)
			)
		)
		(property "Public" ""
			(at 260.65 -34.2 0)
			(layer "F.Fab")
			(hide yes)
			(effects
				(font
					(size 1 1)
					(thickness 0.15)
				)
			)
		)
		(sheetname "Supply")
		(sheetfile "supply.kicad_sch")
		(attr smd exclude_from_bom)
		(fp_line
			(start -0.277 -0.551)
			(end -0.277 -0.75)
			(stroke
				(width 0.15)
				(type solid)
			)
			(layer "F.SilkS")
		)
		(fp_line
			(start -0.725 -0.551)
			(end -0.277 -0.551)
			(stroke
				(width 0.15)
				(type solid)
			)
			(layer "F.SilkS")
		)
		(fp_line
			(start -0.927 -0.351)
			(end -0.725 -0.551)
			(stroke
				(width 0.15)
				(type solid)
			)
			(layer "F.SilkS")
		)
		(fp_line
			(start -0.927 -0.051)
			(end -0.927 -0.351)
			(stroke
				(width 0.15)
				(type solid)
			)
			(layer "F.SilkS")
		)
		(fp_circle
			(center -0.9652 0.9652)
			(end -0.9152 0.9652)
			(stroke
				(width 0.15)
				(type solid)
			)
			(fill solid)
			(layer "F.SilkS")
		)
		(fp_line
			(start 1.1 -1.16)
			(end 1.1 1.15)
			(stroke
				(width 0.05)
				(type solid)
			)
			(layer "F.CrtYd")
		)
		(fp_line
			(start -1.12 -1.16)
			(end 1.1 -1.16)
			(stroke
				(width 0.05)
				(type solid)
			)
			(layer "F.CrtYd")
		)
		(fp_line
			(start -1.12 -1.16)
			(end -1.12 1.15)
			(stroke
				(width 0.05)
				(type solid)
			)
			(layer "F.CrtYd")
		)
		(fp_line
			(start -1.12 1.15)
			(end 1.1 1.15)
			(stroke
				(width 0.05)
				(type solid)
			)
			(layer "F.CrtYd")
		)
		(fp_line
			(start 0.8 -0.425)
			(end -0.652 -0.425)
			(stroke
				(width 0.15)
				(type solid)
			)
			(layer "F.Fab")
		)
		(fp_line
			(start 0.8 -0.425)
			(end 0.8 0.424)
			(stroke
				(width 0.15)
				(type solid)
			)
			(layer "F.Fab")
		)
		(fp_line
			(start -0.652 -0.425)
			(end -0.802 -0.276)
			(stroke
				(width 0.15)
				(type solid)
			)
			(layer "F.Fab")
		)
		(fp_line
			(start -0.802 -0.276)
			(end -0.802 0.424)
			(stroke
				(width 0.15)
				(type solid)
			)
			(layer "F.Fab")
		)
		(fp_line
			(start 0.8 0.424)
			(end -0.802 0.424)
			(stroke
				(width 0.15)
				(type solid)
			)
			(layer "F.Fab")
		)
		(fp_circle
			(center -0.9652 0.9652)
			(end -0.9144 0.9652)
			(stroke
				(width 0.15)
				(type solid)
			)
			(fill none)
			(layer "F.Fab")
		)
		(fp_text user "Author: Antmicro"
			(at -1.12 6.224 90)
			(layer "F.Fab")
			(hide yes)
			(effects
				(font
					(size 0.7 0.7)
					(thickness 0.15)
				)
				(justify left bottom)
			)
		)
		(fp_text user "${REFERENCE}"
			(at -1.12 3.824 90)
			(layer "F.Fab")
			(hide yes)
			(effects
				(font
					(size 0.7 0.7)
					(thickness 0.15)
				)
				(justify left bottom)
			)
		)
		(fp_text user "License: Apache-2.0"
			(at -1.12 5.024 90)
			(layer "F.Fab")
			(hide yes)
			(effects
				(font
					(size 0.7 0.7)
					(thickness 0.15)
				)
				(justify left bottom)
			)
		)
		(pad "1" smd rect
			(at -0.5 0.65 90)
			(size 0.4 0.51)
			(layers "F.Cu" "F.Paste" "F.Mask")
			(net 11 "+1V8")
			(pinfunction "G")
			(pintype "passive")
		)
		(pad "2" smd rect
			(at 0.498 0.65 90)
			(size 0.4 0.51)
			(layers "F.Cu" "F.Paste" "F.Mask")
			(net 1 "GND")
			(pinfunction "S")
			(pintype "passive")
		)
		(pad "3" smd rect
			(at 0 -0.652 90)
			(size 0.4 0.51)
			(layers "F.Cu" "F.Paste" "F.Mask")
			(net 73 "Net-(D8-C)")
			(pinfunction "D")
			(pintype "passive")
		)
	)
)
